# T6G (Grand Teton) — schematic netlist excerpt (pin names and nets, part order shuffled) for the footprints in the layout excerpt that follows; sources: Cadence DE-HDL packaged netlist, KiCad conversion of 04192023_DAF0TMB3IC0_F0TG_MB_C_brd_V02_OCP.brd

R1777  Q_RES  1K 1% CHIP  pkg 0402LF  page 187 : A = P1V5_BAT_IN ; B = BAT_LDO_EN
C873  Q_CAP_DIFFBUS  DIFF BUS_0.22UF 6.3V 20% X6S  pkg C0201  page 64 : \1\ = P5E_CPU0_P3_TX_C_DP<14> ; \2\ = P5E_CPU0_P3_TX_DP<14>
C6525  Q_CAP_DIFFBUS  DIFF BUS_0.22UF 6.3V 20% X6S  pkg C0201  page 275 : \1\ = P5E_CPU0_P0_TX_BUF_C_DP<12> ; \2\ = P5E_CPU0_P0_TX_BUF_DP<12>

(kicad_pcb
	(version 20260206)
	(generator "pcbnew")
	(generator_version "10.0")
	(general
		(thickness 1.6)
		(legacy_teardrops no)
	)
	(paper "A4")
	(title_block
		(title "04192023_DAF0TMB3IC0_F0TG_MB_C_brd_V02_OCP.brd")
		(comment 1 "Grand Teton / footprints 2096-2098 of 8354")
	)
	(layers
		(0 "F.Cu" signal "TOP")
		(4 "In1.Cu" signal "GND")
		(6 "In2.Cu" signal "IN1")
		(8 "In3.Cu" signal "GND1")
		(10 "In4.Cu" signal "IN2")
		(12 "In5.Cu" signal "GND2")
		(14 "In6.Cu" signal "IN3")
		(16 "In7.Cu" signal "GND3")
		(18 "In8.Cu" signal "VCC")
		(20 "In9.Cu" signal "VCC1")
		(22 "In10.Cu" signal "GND4")
		(24 "In11.Cu" signal "IN4")
		(26 "In12.Cu" signal "GND5")
		(28 "In13.Cu" signal "IN5")
		(30 "In14.Cu" signal "GND6")
		(32 "In15.Cu" signal "IN6")
		(34 "In16.Cu" signal "GND7")
		(2 "B.Cu" signal "BOTTOM")
		(9 "F.Adhes" user "F.Adhesive")
		(11 "B.Adhes" user "B.Adhesive")
		(13 "F.Paste" user "Package Geometry/Pastemask Top")
		(15 "B.Paste" user "Package Geometry/Pastemask Bottom")
		(5 "F.SilkS" user "Ref Des/Silkscreen Top")
		(7 "B.SilkS" user "Ref Des/Silkscreen Bottom")
		(1 "F.Mask" user "Board Geometry/Soldermask Top")
		(3 "B.Mask" user "Board Geometry/Soldermask Bottom")
		(17 "Dwgs.User" user "User.Drawings")
		(19 "Cmts.User" user "User.Comments")
		(21 "Eco1.User" user "User.Eco1")
		(23 "Eco2.User" user "User.Eco2")
		(25 "Edge.Cuts" user "Board Geometry/Outline")
		(27 "Margin" user)
		(31 "F.CrtYd" user "Package Geometry/Place Bound Top")
		(29 "B.CrtYd" user "Package Geometry/Place Bound Bottom")
		(35 "F.Fab" user "Ref Des/Assembly Top")
		(33 "B.Fab" user "Ref Des/Assembly Bottom")
	)
	(footprint ""
		(layer "F.Cu")
		(at 300.022514 -24.349456)
		(property "Reference" "R1777"
			(at 0 0 0)
			(layer "F.SilkS")
			(hide yes)
			(effects
				(font
					(size 1.27 1.27)
				)
			)
		)
		(property "Value" ""
			(at 0 0 0)
			(layer "F.Fab")
			(effects
				(font
					(size 1.27 1.27)
				)
			)
		)
		(duplicate_pad_numbers_are_jumpers no)
		(fp_line
			(start -0.7874 -0.4064)
			(end 0.7874 -0.4064)
			(stroke
				(width 0.1524)
				(type default)
			)
			(layer "F.SilkS")
		)
		(fp_line
			(start -0.7874 0.4064)
			(end -0.7874 -0.4064)
			(stroke
				(width 0.1524)
				(type default)
			)
			(layer "F.SilkS")
		)
		(fp_line
			(start 0.7874 -0.4064)
			(end 0.7874 0.4064)
			(stroke
				(width 0.1524)
				(type default)
			)
			(layer "F.SilkS")
		)
		(fp_line
			(start 0.7874 0.4064)
			(end -0.7874 0.4064)
			(stroke
				(width 0.1524)
				(type default)
			)
			(layer "F.SilkS")
		)
		(fp_line
			(start -0.67945 -0.305054)
			(end -0.12065 -0.305054)
			(stroke
				(width 0.1)
				(type default)
			)
			(layer "F.Fab")
		)
		(fp_line
			(start -0.67945 0.3048)
			(end -0.67945 -0.305054)
			(stroke
				(width 0.1)
				(type default)
			)
			(layer "F.Fab")
		)
		(fp_line
			(start -0.12065 -0.305054)
			(end -0.12065 -0.2794)
			(stroke
				(width 0.1)
				(type default)
			)
			(layer "F.Fab")
		)
		(fp_line
			(start -0.12065 -0.2794)
			(end 0.12065 -0.2794)
			(stroke
				(width 0.1)
				(type default)
			)
			(layer "F.Fab")
		)
		(fp_line
			(start -0.12065 0.2794)
			(end -0.12065 0.3048)
			(stroke
				(width 0.1)
				(type default)
			)
			(layer "F.Fab")
		)
		(fp_line
			(start -0.12065 0.3048)
			(end -0.67945 0.3048)
			(stroke
				(width 0.1)
				(type default)
			)
			(layer "F.Fab")
		)
		(fp_line
			(start 0.120396 0.2794)
			(end -0.12065 0.2794)
			(stroke
				(width 0.1)
				(type default)
			)
			(layer "F.Fab")
		)
		(fp_line
			(start 0.120396 0.3048)
			(end 0.120396 0.2794)
			(stroke
				(width 0.1)
				(type default)
			)
			(layer "F.Fab")
		)
		(fp_line
			(start 0.12065 -0.3048)
			(end 0.67945 -0.3048)
			(stroke
				(width 0.1)
				(type default)
			)
			(layer "F.Fab")
		)
		(fp_line
			(start 0.12065 -0.2794)
			(end 0.12065 -0.3048)
			(stroke
				(width 0.1)
				(type default)
			)
			(layer "F.Fab")
		)
		(fp_line
			(start 0.67945 -0.3048)
			(end 0.67945 0.3048)
			(stroke
				(width 0.1)
				(type default)
			)
			(layer "F.Fab")
		)
		(fp_line
			(start 0.67945 0.3048)
			(end 0.120396 0.3048)
			(stroke
				(width 0.1)
				(type default)
			)
			(layer "F.Fab")
		)
		(pad "1" smd circle
			(at -0.40005 0)
			(size 0 0)
			(layers "F.Cu" "F.Mask" "F.Paste")
			(net "P1V5_BAT_IN")
		)
		(pad "2" smd circle
			(at 0.40005 0)
			(size 0 0)
			(layers "F.Cu" "F.Mask" "F.Paste")
			(net "BAT_LDO_EN")
		)
	)
	(footprint ""
		(layer "F.Cu")
		(at 392.840972 -385.364228)
		(property "Reference" "C873"
			(at 0 0 0)
			(layer "F.SilkS")
			(hide yes)
			(effects
				(font
					(size 1.27 1.27)
				)
			)
		)
		(property "Value" ""
			(at 0 0 0)
			(layer "F.Fab")
			(effects
				(font
					(size 1.27 1.27)
				)
			)
		)
		(duplicate_pad_numbers_are_jumpers no)
		(fp_line
			(start -0.299974 -0.150114)
			(end 0.299974 -0.150114)
			(stroke
				(width 0.1)
				(type default)
			)
			(layer "F.Fab")
		)
		(fp_line
			(start -0.299974 0.150114)
			(end -0.299974 -0.150114)
			(stroke
				(width 0.1)
				(type default)
			)
			(layer "F.Fab")
		)
		(fp_line
			(start 0.299974 -0.150114)
			(end 0.299974 0.150114)
			(stroke
				(width 0.1)
				(type default)
			)
			(layer "F.Fab")
		)
		(fp_line
			(start 0.299974 0.150114)
			(end -0.299974 0.150114)
			(stroke
				(width 0.1)
				(type default)
			)
			(layer "F.Fab")
		)
		(pad "1" smd rect
			(at -0.2667 0)
			(size 0.3048 0.381)
			(layers "F.Cu" "F.Mask" "F.Paste")
			(net "P5E_CPU0_P3_TX_C_DP<14>")
		)
		(pad "2" smd rect
			(at 0.2667 0)
			(size 0.3048 0.381)
			(layers "F.Cu" "F.Mask" "F.Paste")
			(net "P5E_CPU0_P3_TX_DP<14>")
		)
	)
	(footprint ""
		(layer "F.Cu")
		(at 341.441786 -416.899344 -90)
		(property "Reference" "C6525"
			(at 0 0 270)
			(layer "F.SilkS")
			(hide yes)
			(effects
				(font
					(size 1.27 1.27)
				)
			)
		)
		(property "Value" ""
			(at 0 0 270)
			(layer "F.Fab")
			(effects
				(font
					(size 1.27 1.27)
				)
			)
		)
		(duplicate_pad_numbers_are_jumpers no)
		(fp_line
			(start -0.299974 0.150114)
			(end -0.299974 -0.150114)
			(stroke
				(width 0.1)
				(type default)
			)
			(layer "F.Fab")
		)
		(fp_line
			(start 0.299974 0.150114)
			(end -0.299974 0.150114)
			(stroke
				(width 0.1)
				(type default)
			)
			(layer "F.Fab")
		)
		(fp_line
			(start -0.299974 -0.150114)
			(end 0.299974 -0.150114)
			(stroke
				(width 0.1)
				(type default)
			)
			(layer "F.Fab")
		)
		(fp_line
			(start 0.299974 -0.150114)
			(end 0.299974 0.150114)
			(stroke
				(width 0.1)
				(type default)
			)
			(layer "F.Fab")
		)
		(pad "1" smd rect
			(at -0.2667 0 270)
			(size 0.3048 0.381)
			(layers "F.Cu" "F.Mask" "F.Paste")
			(net "P5E_CPU0_P0_TX_BUF_C_DP<12>")
		)
		(pad "2" smd rect
			(at 0.2667 0 270)
			(size 0.3048 0.381)
			(layers "F.Cu" "F.Mask" "F.Paste")
			(net "P5E_CPU0_P0_TX_BUF_DP<12>")
		)
	)
)
